# BASEBOARD_FAB2 (Tioga Pass) — schematic netlist excerpt (pin names and nets, part order shuffled) for the footprints in the layout excerpt that follows; sources: Cadence DE-HDL packaged netlist, KiCad conversion of Wiwynn_Tioga_Pass_MB.brd

R1G11  RES  1.00K 1% CHIP  pkg 0402  page 223 : A = P3V3_STBY ; B = IRQ_PVDDQ_GHJ_VRHOT_LVT3_R_N
R1L26  RES  33.2 1% CHIP  pkg 0402  page 175 : A = FM_PWR_BTN_R_N ; B = FM_PWR_BTN_N
C7B12  CAP  1000PF 50V 10% X7R  pkg 0402LF  page 232 : A = PWRGD_PVPP_DEF_R ; B = GND

(kicad_pcb
	(version 20260206)
	(generator "pcbnew")
	(generator_version "10.0")
	(general
		(thickness 1.6)
		(legacy_teardrops no)
	)
	(paper "A4")
	(title_block
		(title "Wiwynn_Tioga_Pass_MB.brd")
		(comment 1 "Tioga Pass / footprints 1312-1314 of 4770")
	)
	(layers
		(0 "F.Cu" signal "TOP")
		(4 "In1.Cu" signal "L2GND")
		(6 "In2.Cu" signal "L3")
		(8 "In3.Cu" signal "L4GND")
		(10 "In4.Cu" signal "L5")
		(12 "In5.Cu" signal "L6GND")
		(14 "In6.Cu" signal "L7VCC")
		(16 "In7.Cu" signal "L8VCC")
		(18 "In8.Cu" signal "L9GND")
		(20 "In9.Cu" signal "L10")
		(22 "In10.Cu" signal "L11GND")
		(24 "In11.Cu" signal "L12")
		(26 "In12.Cu" signal "L13GND")
		(2 "B.Cu" signal "BOTTOM")
		(9 "F.Adhes" user "F.Adhesive")
		(11 "B.Adhes" user "B.Adhesive")
		(13 "F.Paste" user "Package Geometry/Pastemask Top")
		(15 "B.Paste" user "Package Geometry/Pastemask Bottom")
		(5 "F.SilkS" user "Ref Des/Silkscreen Top")
		(7 "B.SilkS" user "Ref Des/Silkscreen Bottom")
		(1 "F.Mask" user "Board Geometry/Soldermask Top")
		(3 "B.Mask" user "Board Geometry/Soldermask Bottom")
		(17 "Dwgs.User" user "User.Drawings")
		(19 "Cmts.User" user "User.Comments")
		(21 "Eco1.User" user "User.Eco1")
		(23 "Eco2.User" user "User.Eco2")
		(25 "Edge.Cuts" user "Board Geometry/Outline")
		(27 "Margin" user)
		(31 "F.CrtYd" user "Package Geometry/Place Bound Top")
		(29 "B.CrtYd" user "Package Geometry/Place Bound Bottom")
		(35 "F.Fab" user "Ref Des/Assembly Top")
		(33 "B.Fab" user "Ref Des/Assembly Bottom")
	)
	(footprint ""
		(layer "F.Cu")
		(at 13.438124 -4.426204)
		(property "Reference" "R1G11"
			(at 0 0 0)
			(layer "F.SilkS")
			(hide yes)
			(effects
				(font
					(size 1.27 1.27)
				)
			)
		)
		(property "Value" ""
			(at 0 0 0)
			(layer "F.Fab")
			(effects
				(font
					(size 1.27 1.27)
				)
			)
		)
		(duplicate_pad_numbers_are_jumpers no)
		(fp_poly
			(pts
				(xy -0.2794 -0.1016) (xy 0.2794 -0.1016) (xy 0.2794 0.9906) (xy -0.2794 0.9906)
			)
			(stroke
				(width 0)
				(type default)
			)
			(fill no)
			(layer "F.CrtYd")
		)
		(fp_line
			(start -0.2794 -0.1016)
			(end -0.2794 0.9906)
			(stroke
				(width 0.1)
				(type default)
			)
			(layer "F.Fab")
		)
		(fp_line
			(start -0.2794 0.9906)
			(end 0.2794 0.9906)
			(stroke
				(width 0.1)
				(type default)
			)
			(layer "F.Fab")
		)
		(fp_line
			(start 0.2794 -0.1016)
			(end -0.2794 -0.1016)
			(stroke
				(width 0.1)
				(type default)
			)
			(layer "F.Fab")
		)
		(fp_line
			(start 0.2794 0.9906)
			(end 0.2794 -0.1016)
			(stroke
				(width 0.1)
				(type default)
			)
			(layer "F.Fab")
		)
		(pad "1" smd rect
			(at 0 0)
			(size 0.508 0.508)
			(layers "F.Cu" "F.Mask" "F.Paste")
			(net "P3V3_STBY")
		)
		(pad "2" smd rect
			(at 0 0.889)
			(size 0.508 0.508)
			(layers "F.Cu" "F.Mask" "F.Paste")
			(net "IRQ_PVDDQ_GHJ_VRHOT_LVT3_R_N")
		)
		(zone
			(layer "F.Cu")
			(hatch none 0.5)
			(connect_pads
				(clearance 0)
			)
			(min_thickness 0.25)
			(keepout
				(tracks allowed)
				(vias not_allowed)
				(pads allowed)
				(copperpour not_allowed)
				(footprints allowed)
			)
			(placement
				(enabled no)
				(sheetname "")
			)
			(fill
				(thermal_gap 0.5)
				(thermal_bridge_width 0.5)
				(island_removal_mode 0)
			)
			(polygon
				(pts
					(xy 13.184124 -4.172204) (xy 13.692124 -4.172204) (xy 13.692124 -3.791204) (xy 13.184124 -3.791204)
				)
			)
		)
		(zone
			(layer "F.Cu")
			(hatch none 0.5)
			(connect_pads
				(clearance 0)
			)
			(min_thickness 0.25)
			(keepout
				(tracks not_allowed)
				(vias allowed)
				(pads allowed)
				(copperpour not_allowed)
				(footprints allowed)
			)
			(placement
				(enabled no)
				(sheetname "")
			)
			(fill
				(thermal_gap 0.5)
				(thermal_bridge_width 0.5)
				(island_removal_mode 0)
			)
			(polygon
				(pts
					(xy 13.184124 -3.791204) (xy 13.692124 -3.791204) (xy 13.692124 -4.172204) (xy 13.184124 -4.172204)
				)
			)
		)
	)
	(footprint ""
		(layer "F.Cu")
		(at 346.202 -127.127 90)
		(property "Reference" "C7B12"
			(at 0 0 90)
			(layer "F.SilkS")
			(hide yes)
			(effects
				(font
					(size 1.27 1.27)
				)
			)
		)
		(property "Value" ""
			(at 0 0 90)
			(layer "F.Fab")
			(effects
				(font
					(size 1.27 1.27)
				)
			)
		)
		(duplicate_pad_numbers_are_jumpers no)
		(fp_poly
			(pts
				(xy 0.3048 -0.1016) (xy 0.3048 0.9906) (xy -0.3048 0.9906) (xy -0.3048 -0.1016)
			)
			(stroke
				(width 0)
				(type default)
			)
			(fill no)
			(layer "F.CrtYd")
		)
		(fp_line
			(start 0.3048 -0.1016)
			(end -0.3048 -0.1016)
			(stroke
				(width 0.1)
				(type default)
			)
			(layer "F.Fab")
		)
		(fp_line
			(start -0.3048 -0.1016)
			(end -0.3048 0.9906)
			(stroke
				(width 0.1)
				(type default)
			)
			(layer "F.Fab")
		)
		(fp_line
			(start 0.3048 0.9906)
			(end 0.3048 -0.1016)
			(stroke
				(width 0.1)
				(type default)
			)
			(layer "F.Fab")
		)
		(fp_line
			(start -0.3048 0.9906)
			(end 0.3048 0.9906)
			(stroke
				(width 0.1)
				(type default)
			)
			(layer "F.Fab")
		)
		(pad "1" smd rect
			(at 0 0 90)
			(size 0.508 0.508)
			(layers "F.Cu" "F.Mask" "F.Paste")
			(net "PWRGD_PVPP_DEF_R")
		)
		(pad "2" smd rect
			(at 0 0.889 90)
			(size 0.508 0.508)
			(layers "F.Cu" "F.Mask" "F.Paste")
			(net "GND")
		)
		(zone
			(layer "F.Cu")
			(hatch none 0.5)
			(connect_pads
				(clearance 0)
			)
			(min_thickness 0.25)
			(keepout
				(tracks allowed)
				(vias not_allowed)
				(pads allowed)
				(copperpour not_allowed)
				(footprints allowed)
			)
			(placement
				(enabled no)
				(sheetname "")
			)
			(fill
				(thermal_gap 0.5)
				(thermal_bridge_width 0.5)
				(island_removal_mode 0)
			)
			(polygon
				(pts
					(xy 346.456 -126.873) (xy 346.456 -127.381) (xy 346.837 -127.381) (xy 346.837 -126.873)
				)
			)
		)
		(zone
			(layer "F.Cu")
			(hatch none 0.5)
			(connect_pads
				(clearance 0)
			)
			(min_thickness 0.25)
			(keepout
				(tracks not_allowed)
				(vias allowed)
				(pads allowed)
				(copperpour not_allowed)
				(footprints allowed)
			)
			(placement
				(enabled no)
				(sheetname "")
			)
			(fill
				(thermal_gap 0.5)
				(thermal_bridge_width 0.5)
				(island_removal_mode 0)
			)
			(polygon
				(pts
					(xy 346.837 -126.873) (xy 346.837 -127.381) (xy 346.456 -127.381) (xy 346.456 -126.873)
				)
			)
		)
	)
	(footprint ""
		(layer "F.Cu")
		(at 478.5995 -142.875 -90)
		(property "Reference" "R1L26"
			(at 0 0 270)
			(layer "F.SilkS")
			(hide yes)
			(effects
				(font
					(size 1.27 1.27)
				)
			)
		)
		(property "Value" ""
			(at 0 0 270)
			(layer "F.Fab")
			(effects
				(font
					(size 1.27 1.27)
				)
			)
		)
		(duplicate_pad_numbers_are_jumpers no)
		(fp_poly
			(pts
				(xy -0.2794 -0.1016) (xy 0.2794 -0.1016) (xy 0.2794 0.9906) (xy -0.2794 0.9906)
			)
			(stroke
				(width 0)
				(type default)
			)
			(fill no)
			(layer "F.CrtYd")
		)
		(fp_line
			(start -0.2794 0.9906)
			(end 0.2794 0.9906)
			(stroke
				(width 0.1)
				(type default)
			)
			(layer "F.Fab")
		)
		(fp_line
			(start 0.2794 0.9906)
			(end 0.2794 -0.1016)
			(stroke
				(width 0.1)
				(type default)
			)
			(layer "F.Fab")
		)
		(fp_line
			(start -0.2794 -0.1016)
			(end -0.2794 0.9906)
			(stroke
				(width 0.1)
				(type default)
			)
			(layer "F.Fab")
		)
		(fp_line
			(start 0.2794 -0.1016)
			(end -0.2794 -0.1016)
			(stroke
				(width 0.1)
				(type default)
			)
			(layer "F.Fab")
		)
		(pad "1" smd rect
			(at 0 0 270)
			(size 0.508 0.508)
			(layers "F.Cu" "F.Mask" "F.Paste")
			(net "FM_PWR_BTN_R_N")
		)
		(pad "2" smd rect
			(at 0 0.889 270)
			(size 0.508 0.508)
			(layers "F.Cu" "F.Mask" "F.Paste")
			(net "FM_PWR_BTN_N")
		)
		(zone
			(layer "F.Cu")
			(hatch none 0.5)
			(connect_pads
				(clearance 0)
			)
			(min_thickness 0.25)
			(keepout
				(tracks not_allowed)
				(vias allowed)
				(pads allowed)
				(copperpour not_allowed)
				(footprints allowed)
			)
			(placement
				(enabled no)
				(sheetname "")
			)
			(fill
				(thermal_gap 0.5)
				(thermal_bridge_width 0.5)
				(island_removal_mode 0)
			)
			(polygon
				(pts
					(xy 477.9645 -143.129) (xy 477.9645 -142.621) (xy 478.3455 -142.621) (xy 478.3455 -143.129)
				)
			)
		)
		(zone
			(layer "F.Cu")
			(hatch none 0.5)
			(connect_pads
				(clearance 0)
			)
			(min_thickness 0.25)
			(keepout
				(tracks allowed)
				(vias not_allowed)
				(pads allowed)
				(copperpour not_allowed)
				(footprints allowed)
			)
			(placement
				(enabled no)
				(sheetname "")
			)
			(fill
				(thermal_gap 0.5)
				(thermal_bridge_width 0.5)
				(island_removal_mode 0)
			)
			(polygon
				(pts
					(xy 478.3455 -143.129) (xy 478.3455 -142.621) (xy 477.9645 -142.621) (xy 477.9645 -143.129)
				)
			)
		)
	)
)
